(kicad_pcb
	(version 20260206)
	(generator "pcbnew")
	(generator_version "10.0")
	(general
		(thickness 1.6)
		(legacy_teardrops no)
	)
	(paper "A4")
	(title_block
		(title "panther-plus-userver — 13130-1b_20150205.brd")
		(comment 1 "Honey Badger (Wiwynn) / footprints 350-358 of 1509")
	)
	(layers
		(0 "F.Cu" signal "TOP")
		(4 "In1.Cu" signal "L2")
		(6 "In2.Cu" signal "L3")
		(8 "In3.Cu" signal "L4")
		(10 "In4.Cu" signal "L5")
		(12 "In5.Cu" signal "L6")
		(14 "In6.Cu" signal "L7")
		(16 "In7.Cu" signal "L8")
		(18 "In8.Cu" signal "L9")
		(20 "In9.Cu" signal "L10")
		(22 "In10.Cu" signal "L11")
		(2 "B.Cu" signal "BOTTOM")
		(9 "F.Adhes" user "F.Adhesive")
		(11 "B.Adhes" user "B.Adhesive")
		(13 "F.Paste" user "Package Geometry/Pastemask Top")
		(15 "B.Paste" user "Package Geometry/Pastemask Bottom")
		(5 "F.SilkS" user "Ref Des/Silkscreen Top")
		(7 "B.SilkS" user "Ref Des/Silkscreen Bottom")
		(1 "F.Mask" user "Board Geometry/Soldermask Top")
		(3 "B.Mask" user "Board Geometry/Soldermask Bottom")
		(17 "Dwgs.User" user "User.Drawings")
		(19 "Cmts.User" user "User.Comments")
		(21 "Eco1.User" user "User.Eco1")
		(23 "Eco2.User" user "User.Eco2")
		(25 "Edge.Cuts" user "Board Geometry/Outline")
		(27 "Margin" user)
		(31 "F.CrtYd" user "Package Geometry/Place Bound Top")
		(29 "B.CrtYd" user "Package Geometry/Place Bound Bottom")
		(35 "F.Fab" user "Ref Des/Assembly Top")
		(33 "B.Fab" user "Ref Des/Assembly Bottom")
	)
	(footprint ""
		(layer "F.Cu")
		(at 111.506 -20.193 -90)
		(property "Reference" "R161"
			(at 0 0 270)
			(layer "F.SilkS")
			(hide yes)
			(effects
				(font
					(size 1.27 1.27)
				)
			)
		)
		(property "Value" "100R2F-L1-GP-U"
			(at 0.064008 -3.993896 270)
			(unlocked yes)
			(layer "F.Fab")
			(hide yes)
			(effects
				(font
					(size 1.016 1.016)
					(thickness 0.1524)
				)
			)
		)
		(property "Device Type" "R402H14"
			(at 0.064008 -5.517896 270)
			(unlocked yes)
			(layer "F.Fab")
			(hide yes)
			(effects
				(font
					(size 1.016 1.016)
					(thickness 0.1524)
				)
			)
		)
		(duplicate_pad_numbers_are_jumpers no)
		(fp_rect
			(start -0.381 0.8382)
			(end 0.381 -0.8382)
			(stroke
				(width 0)
				(type default)
			)
			(fill no)
			(layer "F.CrtYd")
		)
		(fp_rect
			(start -0.381 0.8382)
			(end 0.381 -0.8382)
			(stroke
				(width 0)
				(type default)
			)
			(fill no)
			(layer "F.Fab")
		)
		(pad "1" smd custom
			(at 0 -0.4318 270)
			(size 0.127 0.127)
			(layers "F.Cu" "F.Mask" "F.Paste")
			(net "M_B_MON1_P")
			(options
				(clearance outline)
				(anchor circle)
			)
			(primitives
				(gr_poly
					(pts
						(arc
							(start -0.2032 -0.2794)
							(mid -0.239121 -0.264521)
							(end -0.254 -0.2286)
						)
						(arc
							(start -0.254 0.2286)
							(mid -0.239121 0.264521)
							(end -0.2032 0.2794)
						)
						(arc
							(start 0.2032 0.2794)
							(mid 0.239121 0.264521)
							(end 0.254 0.2286)
						)
						(arc
							(start 0.254 -0.2286)
							(mid 0.239121 -0.264521)
							(end 0.2032 -0.2794)
						)
					)
					(width 0)
					(fill yes)
				)
			)
		)
		(pad "2" smd custom
			(at 0 0.4318 270)
			(size 0.127 0.127)
			(layers "F.Cu" "F.Mask" "F.Paste")
			(net "M_B_MON1_N")
			(options
				(clearance outline)
				(anchor circle)
			)
			(primitives
				(gr_poly
					(pts
						(arc
							(start -0.2032 -0.2794)
							(mid -0.239121 -0.264521)
							(end -0.254 -0.2286)
						)
						(arc
							(start -0.254 0.2286)
							(mid -0.239121 0.264521)
							(end -0.2032 0.2794)
						)
						(arc
							(start 0.2032 0.2794)
							(mid 0.239121 0.264521)
							(end 0.254 0.2286)
						)
						(arc
							(start 0.254 -0.2286)
							(mid 0.239121 -0.264521)
							(end 0.2032 -0.2794)
						)
					)
					(width 0)
					(fill yes)
				)
			)
		)
	)
	(footprint ""
		(layer "F.Cu")
		(at 157.48 -23.876)
		(property "Reference" "TP62"
			(at 0 0 0)
			(layer "F.SilkS")
			(hide yes)
			(effects
				(font
					(size 1.27 1.27)
				)
			)
		)
		(property "Value" "TPAD28-1-GP-U"
			(at 0.0508 -1.9304 0)
			(unlocked yes)
			(layer "F.Fab")
			(hide yes)
			(effects
				(font
					(size 1.016 1.016)
					(thickness 0.1524)
				)
			)
		)
		(property "Device Type" "TPAD28-1-U"
			(at 0.0508 -3.4544 0)
			(unlocked yes)
			(layer "F.Fab")
			(hide yes)
			(effects
				(font
					(size 1.016 1.016)
					(thickness 0.1524)
				)
			)
		)
		(duplicate_pad_numbers_are_jumpers no)
		(fp_poly
			(pts
				(arc
					(start 0.3556 0)
					(mid -0.3556 0)
					(end 0.3556 0)
				)
			)
			(stroke
				(width 0)
				(type default)
			)
			(fill no)
			(layer "F.CrtYd")
		)
		(fp_poly
			(pts
				(arc
					(start 0.9525 0)
					(mid -0.9525 0)
					(end 0.9525 0)
				)
			)
			(stroke
				(width 0)
				(type default)
			)
			(fill no)
			(layer "F.Fab")
		)
		(pad "1" smd circle
			(at 0 0)
			(size 0.7112 0.7112)
			(layers "F.Cu" "F.Mask" "F.Paste")
			(net "TP_FPGA_P112")
		)
	)
	(footprint ""
		(layer "F.Cu")
		(at 18.542 -33.147)
		(property "Reference" "PC174"
			(at 0 0 0)
			(layer "F.SilkS")
			(hide yes)
			(effects
				(font
					(size 1.27 1.27)
				)
			)
		)
		(property "Value" "SC1KP50V2KX-1GP"
			(at 1.8923 -1.2065 0)
			(unlocked yes)
			(layer "F.Fab")
			(hide yes)
			(effects
				(font
					(size 1.016 1.016)
					(thickness 0.1524)
				)
			)
		)
		(property "Device Type" "C402H22"
			(at 1.8923 -2.7305 0)
			(unlocked yes)
			(layer "F.Fab")
			(hide yes)
			(effects
				(font
					(size 1.016 1.016)
					(thickness 0.1524)
				)
			)
		)
		(duplicate_pad_numbers_are_jumpers no)
		(fp_rect
			(start -0.381 0.7366)
			(end 0.381 -0.7366)
			(stroke
				(width 0)
				(type default)
			)
			(fill no)
			(layer "F.CrtYd")
		)
		(fp_rect
			(start -0.381 0.7366)
			(end 0.381 -0.7366)
			(stroke
				(width 0)
				(type default)
			)
			(fill no)
			(layer "F.Fab")
		)
		(pad "1" smd custom
			(at 0 -0.4572)
			(size 0.1143 0.1143)
			(layers "F.Cu" "F.Mask" "F.Paste")
			(net "P3V3_STBY_LL_R")
			(options
				(clearance outline)
				(anchor circle)
			)
			(primitives
				(gr_poly
					(pts
						(arc
							(start -0.254 -0.1778)
							(mid -0.239121 -0.213721)
							(end -0.2032 -0.2286)
						)
						(arc
							(start 0.2032 -0.2286)
							(mid 0.239121 -0.213721)
							(end 0.254 -0.1778)
						)
						(arc
							(start 0.254 0.1778)
							(mid 0.239121 0.213721)
							(end 0.2032 0.2286)
						)
						(arc
							(start -0.2032 0.2286)
							(mid -0.239121 0.213721)
							(end -0.254 0.1778)
						)
					)
					(width 0)
					(fill yes)
				)
			)
		)
		(pad "2" smd custom
			(at 0 0.4572)
			(size 0.1143 0.1143)
			(layers "F.Cu" "F.Mask" "F.Paste")
			(net "P3V3_STBY_VFB")
			(options
				(clearance outline)
				(anchor circle)
			)
			(primitives
				(gr_poly
					(pts
						(arc
							(start -0.254 -0.1778)
							(mid -0.239121 -0.213721)
							(end -0.2032 -0.2286)
						)
						(arc
							(start 0.2032 -0.2286)
							(mid 0.239121 -0.213721)
							(end 0.254 -0.1778)
						)
						(arc
							(start 0.254 0.1778)
							(mid 0.239121 0.213721)
							(end 0.2032 0.2286)
						)
						(arc
							(start -0.2032 0.2286)
							(mid -0.239121 0.213721)
							(end -0.254 0.1778)
						)
					)
					(width 0)
					(fill yes)
				)
			)
		)
	)
	(footprint ""
		(layer "F.Cu")
		(at 114.808 -71.12)
		(property "Reference" "R229"
			(at 0 0 0)
			(layer "F.SilkS")
			(hide yes)
			(effects
				(font
					(size 1.27 1.27)
				)
			)
		)
		(property "Value" "4K7R2F-GP"
			(at 0.064008 -3.993896 0)
			(unlocked yes)
			(layer "F.Fab")
			(hide yes)
			(effects
				(font
					(size 1.016 1.016)
					(thickness 0.1524)
				)
			)
		)
		(property "Device Type" "R402H16"
			(at 0.064008 -5.517896 0)
			(unlocked yes)
			(layer "F.Fab")
			(hide yes)
			(effects
				(font
					(size 1.016 1.016)
					(thickness 0.1524)
				)
			)
		)
		(duplicate_pad_numbers_are_jumpers no)
		(fp_rect
			(start -0.381 0.8382)
			(end 0.381 -0.8382)
			(stroke
				(width 0)
				(type default)
			)
			(fill no)
			(layer "F.CrtYd")
		)
		(fp_rect
			(start -0.381 0.8382)
			(end 0.381 -0.8382)
			(stroke
				(width 0)
				(type default)
			)
			(fill no)
			(layer "F.Fab")
		)
		(pad "1" smd custom
			(at 0 -0.4318)
			(size 0.127 0.127)
			(layers "F.Cu" "F.Mask" "F.Paste")
			(net "CHA_1_SA1")
			(options
				(clearance outline)
				(anchor circle)
			)
			(primitives
				(gr_poly
					(pts
						(arc
							(start -0.2032 -0.2794)
							(mid -0.239121 -0.264521)
							(end -0.254 -0.2286)
						)
						(arc
							(start -0.254 0.2286)
							(mid -0.239121 0.264521)
							(end -0.2032 0.2794)
						)
						(arc
							(start 0.2032 0.2794)
							(mid 0.239121 0.264521)
							(end 0.254 0.2286)
						)
						(arc
							(start 0.254 -0.2286)
							(mid 0.239121 -0.264521)
							(end 0.2032 -0.2794)
						)
					)
					(width 0)
					(fill yes)
				)
			)
		)
		(pad "2" smd custom
			(at 0 0.4318)
			(size 0.127 0.127)
			(layers "F.Cu" "F.Mask" "F.Paste")
			(net "GND")
			(options
				(clearance outline)
				(anchor circle)
			)
			(primitives
				(gr_poly
					(pts
						(arc
							(start -0.2032 -0.2794)
							(mid -0.239121 -0.264521)
							(end -0.254 -0.2286)
						)
						(arc
							(start -0.254 0.2286)
							(mid -0.239121 0.264521)
							(end -0.2032 0.2794)
						)
						(arc
							(start 0.2032 0.2794)
							(mid 0.239121 0.264521)
							(end 0.254 0.2286)
						)
						(arc
							(start 0.254 -0.2286)
							(mid 0.239121 -0.264521)
							(end 0.2032 -0.2794)
						)
					)
					(width 0)
					(fill yes)
				)
			)
		)
	)
	(footprint ""
		(layer "F.Cu")
		(at 142.748 -21.59 180)
		(property "Reference" "TP42"
			(at 0 0 180)
			(layer "F.SilkS")
			(hide yes)
			(effects
				(font
					(size 1.27 1.27)
				)
			)
		)
		(property "Value" "TPAD32-GP"
			(at 0 -3.166364 180)
			(unlocked yes)
			(layer "F.Fab")
			(hide yes)
			(effects
				(font
					(size 1.016 1.016)
					(thickness 0.1524)
				)
			)
		)
		(property "Device Type" "TPAD32"
			(at 0 -4.690618 180)
			(unlocked yes)
			(layer "F.Fab")
			(hide yes)
			(effects
				(font
					(size 1.016 1.016)
					(thickness 0.1524)
				)
			)
		)
		(duplicate_pad_numbers_are_jumpers no)
		(fp_poly
			(pts
				(arc
					(start -0.7112 0)
					(mid 0.7112 0)
					(end -0.7112 0)
				)
			)
			(stroke
				(width 0)
				(type default)
			)
			(fill no)
			(layer "F.CrtYd")
		)
		(fp_poly
			(pts
				(arc
					(start -0.7112 0)
					(mid 0.7112 0)
					(end -0.7112 0)
				)
			)
			(stroke
				(width 0)
				(type default)
			)
			(fill no)
			(layer "F.Fab")
		)
		(pad "1" smd circle
			(at 0 0 180)
			(size 0.8128 0.8128)
			(layers "F.Cu" "F.Mask" "F.Paste")
			(net "C_CONF_DONE")
		)
	)
	(footprint ""
		(layer "F.Cu")
		(at 73.787 -20.32)
		(property "Reference" "R443"
			(at 0 0 0)
			(layer "F.SilkS")
			(hide yes)
			(effects
				(font
					(size 1.27 1.27)
				)
			)
		)
		(property "Value" "0R2J-2-GP"
			(at 1.7907 -1.1176 0)
			(unlocked yes)
			(layer "F.Fab")
			(hide yes)
			(effects
				(font
					(size 1.016 1.016)
					(thickness 0.1524)
				)
			)
		)
		(property "Device Type" "R402H16"
			(at 1.7907 -2.6416 0)
			(unlocked yes)
			(layer "F.Fab")
			(hide yes)
			(effects
				(font
					(size 1.016 1.016)
					(thickness 0.1524)
				)
			)
		)
		(duplicate_pad_numbers_are_jumpers no)
		(fp_rect
			(start -0.381 0.8382)
			(end 0.381 -0.8382)
			(stroke
				(width 0)
				(type default)
			)
			(fill no)
			(layer "F.CrtYd")
		)
		(fp_rect
			(start -0.381 0.8382)
			(end 0.381 -0.8382)
			(stroke
				(width 0)
				(type default)
			)
			(fill no)
			(layer "F.Fab")
		)
		(pad "1" smd custom
			(at 0 -0.4318)
			(size 0.127 0.127)
			(layers "F.Cu" "F.Mask" "F.Paste")
			(net "CPU_RXD")
			(options
				(clearance outline)
				(anchor circle)
			)
			(primitives
				(gr_poly
					(pts
						(arc
							(start -0.2032 -0.2794)
							(mid -0.239121 -0.264521)
							(end -0.254 -0.2286)
						)
						(arc
							(start -0.254 0.2286)
							(mid -0.239121 0.264521)
							(end -0.2032 0.2794)
						)
						(arc
							(start 0.2032 0.2794)
							(mid 0.239121 0.264521)
							(end 0.254 0.2286)
						)
						(arc
							(start 0.254 -0.2286)
							(mid 0.239121 -0.264521)
							(end 0.2032 -0.2794)
						)
					)
					(width 0)
					(fill yes)
				)
			)
		)
		(pad "2" smd custom
			(at 0 0.4318)
			(size 0.127 0.127)
			(layers "F.Cu" "F.Mask" "F.Paste")
			(net "GF_CPU_RXD")
			(options
				(clearance outline)
				(anchor circle)
			)
			(primitives
				(gr_poly
					(pts
						(arc
							(start -0.2032 -0.2794)
							(mid -0.239121 -0.264521)
							(end -0.254 -0.2286)
						)
						(arc
							(start -0.254 0.2286)
							(mid -0.239121 0.264521)
							(end -0.2032 0.2794)
						)
						(arc
							(start 0.2032 0.2794)
							(mid 0.239121 0.264521)
							(end 0.254 0.2286)
						)
						(arc
							(start 0.254 -0.2286)
							(mid 0.239121 -0.264521)
							(end 0.2032 -0.2794)
						)
					)
					(width 0)
					(fill yes)
				)
			)
		)
	)
	(footprint ""
		(layer "F.Cu")
		(at 143.891 -57.658 -90)
		(property "Reference" "C10"
			(at 0 0 270)
			(layer "F.SilkS")
			(hide yes)
			(effects
				(font
					(size 1.27 1.27)
				)
			)
		)
		(property "Value" "SCD1U10V2KX-5GP"
			(at 1.1811 -2.7051 270)
			(unlocked yes)
			(layer "F.Fab")
			(hide yes)
			(effects
				(font
					(size 1.016 1.016)
					(thickness 0.1524)
				)
			)
		)
		(property "Device Type" "C402H22"
			(at 1.1811 -4.2291 270)
			(unlocked yes)
			(layer "F.Fab")
			(hide yes)
			(effects
				(font
					(size 1.016 1.016)
					(thickness 0.1524)
				)
			)
		)
		(duplicate_pad_numbers_are_jumpers no)
		(fp_rect
			(start -0.381 0.7366)
			(end 0.381 -0.7366)
			(stroke
				(width 0)
				(type default)
			)
			(fill no)
			(layer "F.CrtYd")
		)
		(fp_rect
			(start -0.381 0.7366)
			(end 0.381 -0.7366)
			(stroke
				(width 0)
				(type default)
			)
			(fill no)
			(layer "F.Fab")
		)
		(pad "1" smd custom
			(at 0 -0.4572 270)
			(size 0.1143 0.1143)
			(layers "F.Cu" "F.Mask" "F.Paste")
			(net "GND")
			(options
				(clearance outline)
				(anchor circle)
			)
			(primitives
				(gr_poly
					(pts
						(arc
							(start -0.254 -0.1778)
							(mid -0.239121 -0.213721)
							(end -0.2032 -0.2286)
						)
						(arc
							(start 0.2032 -0.2286)
							(mid 0.239121 -0.213721)
							(end 0.254 -0.1778)
						)
						(arc
							(start 0.254 0.1778)
							(mid 0.239121 0.213721)
							(end 0.2032 0.2286)
						)
						(arc
							(start -0.2032 0.2286)
							(mid -0.239121 0.213721)
							(end -0.254 0.1778)
						)
					)
					(width 0)
					(fill yes)
				)
			)
		)
		(pad "2" smd custom
			(at 0 0.4572 270)
			(size 0.1143 0.1143)
			(layers "F.Cu" "F.Mask" "F.Paste")
			(net "P3V3_STBY")
			(options
				(clearance outline)
				(anchor circle)
			)
			(primitives
				(gr_poly
					(pts
						(arc
							(start -0.254 -0.1778)
							(mid -0.239121 -0.213721)
							(end -0.2032 -0.2286)
						)
						(arc
							(start 0.2032 -0.2286)
							(mid 0.239121 -0.213721)
							(end 0.254 -0.1778)
						)
						(arc
							(start 0.254 0.1778)
							(mid 0.239121 0.213721)
							(end 0.2032 0.2286)
						)
						(arc
							(start -0.2032 0.2286)
							(mid -0.239121 0.213721)
							(end -0.254 0.1778)
						)
					)
					(width 0)
					(fill yes)
				)
			)
		)
	)
	(footprint ""
		(layer "F.Cu")
		(at 74.041 -30.734 90)
		(property "Reference" "R347"
			(at 0 0 90)
			(layer "F.SilkS")
			(hide yes)
			(effects
				(font
					(size 1.27 1.27)
				)
			)
		)
		(property "Value" "1KR2F-3-GP"
			(at 0.064008 -3.993896 90)
			(unlocked yes)
			(layer "F.Fab")
			(hide yes)
			(effects
				(font
					(size 1.016 1.016)
					(thickness 0.1524)
				)
			)
		)
		(property "Device Type" "R402H16"
			(at 0.064008 -5.517896 90)
			(unlocked yes)
			(layer "F.Fab")
			(hide yes)
			(effects
				(font
					(size 1.016 1.016)
					(thickness 0.1524)
				)
			)
		)
		(duplicate_pad_numbers_are_jumpers no)
		(fp_rect
			(start -0.381 0.8382)
			(end 0.381 -0.8382)
			(stroke
				(width 0)
				(type default)
			)
			(fill no)
			(layer "F.CrtYd")
		)
		(fp_rect
			(start -0.381 0.8382)
			(end 0.381 -0.8382)
			(stroke
				(width 0)
				(type default)
			)
			(fill no)
			(layer "F.Fab")
		)
		(pad "1" smd custom
			(at 0 -0.4318 90)
			(size 0.127 0.127)
			(layers "F.Cu" "F.Mask" "F.Paste")
			(net "DDR3_DRAM_PWROK")
			(options
				(clearance outline)
				(anchor circle)
			)
			(primitives
				(gr_poly
					(pts
						(arc
							(start -0.2032 -0.2794)
							(mid -0.239121 -0.264521)
							(end -0.254 -0.2286)
						)
						(arc
							(start -0.254 0.2286)
							(mid -0.239121 0.264521)
							(end -0.2032 0.2794)
						)
						(arc
							(start 0.2032 0.2794)
							(mid 0.239121 0.264521)
							(end 0.254 0.2286)
						)
						(arc
							(start 0.254 -0.2286)
							(mid 0.239121 -0.264521)
							(end 0.2032 -0.2794)
						)
					)
					(width 0)
					(fill yes)
				)
			)
		)
		(pad "2" smd custom
			(at 0 0.4318 90)
			(size 0.127 0.127)
			(layers "F.Cu" "F.Mask" "F.Paste")
			(net "PMU_SLP_S45#")
			(options
				(clearance outline)
				(anchor circle)
			)
			(primitives
				(gr_poly
					(pts
						(arc
							(start -0.2032 -0.2794)
							(mid -0.239121 -0.264521)
							(end -0.254 -0.2286)
						)
						(arc
							(start -0.254 0.2286)
							(mid -0.239121 0.264521)
							(end -0.2032 0.2794)
						)
						(arc
							(start 0.2032 0.2794)
							(mid 0.239121 0.264521)
							(end 0.254 0.2286)
						)
						(arc
							(start 0.254 -0.2286)
							(mid 0.239121 -0.264521)
							(end 0.2032 -0.2794)
						)
					)
					(width 0)
					(fill yes)
				)
			)
		)
	)
	(footprint ""
		(layer "F.Cu")
		(at 4.572 -50.419 180)
		(property "Reference" "C4"
			(at 0 0 180)
			(layer "F.SilkS")
			(hide yes)
			(effects
				(font
					(size 1.27 1.27)
				)
			)
		)
		(property "Value" "SCD1U16V2KX-3GP"
			(at 1.1811 -2.7051 180)
			(unlocked yes)
			(layer "F.Fab")
			(hide yes)
			(effects
				(font
					(size 1.016 1.016)
					(thickness 0.1524)
				)
			)
		)
		(property "Device Type" "C402H22"
			(at 1.1811 -4.2291 180)
			(unlocked yes)
			(layer "F.Fab")
			(hide yes)
			(effects
				(font
					(size 1.016 1.016)
					(thickness 0.1524)
				)
			)
		)
		(duplicate_pad_numbers_are_jumpers no)
		(fp_rect
			(start -0.381 0.7366)
			(end 0.381 -0.7366)
			(stroke
				(width 0)
				(type default)
			)
			(fill no)
			(layer "F.CrtYd")
		)
		(fp_rect
			(start -0.381 0.7366)
			(end 0.381 -0.7366)
			(stroke
				(width 0)
				(type default)
			)
			(fill no)
			(layer "F.Fab")
		)
		(pad "1" smd custom
			(at 0 -0.4572 180)
			(size 0.1143 0.1143)
			(layers "F.Cu" "F.Mask" "F.Paste")
			(net "P3V3_STBY")
			(options
				(clearance outline)
				(anchor circle)
			)
			(primitives
				(gr_poly
					(pts
						(arc
							(start -0.254 -0.1778)
							(mid -0.239121 -0.213721)
							(end -0.2032 -0.2286)
						)
						(arc
							(start 0.2032 -0.2286)
							(mid 0.239121 -0.213721)
							(end 0.254 -0.1778)
						)
						(arc
							(start 0.254 0.1778)
							(mid 0.239121 0.213721)
							(end 0.2032 0.2286)
						)
						(arc
							(start -0.2032 0.2286)
							(mid -0.239121 0.213721)
							(end -0.254 0.1778)
						)
					)
					(width 0)
					(fill yes)
				)
			)
		)
		(pad "2" smd custom
			(at 0 0.4572 180)
			(size 0.1143 0.1143)
			(layers "F.Cu" "F.Mask" "F.Paste")
			(net "GND")
			(options
				(clearance outline)
				(anchor circle)
			)
			(primitives
				(gr_poly
					(pts
						(arc
							(start -0.254 -0.1778)
							(mid -0.239121 -0.213721)
							(end -0.2032 -0.2286)
						)
						(arc
							(start 0.2032 -0.2286)
							(mid 0.239121 -0.213721)
							(end 0.254 -0.1778)
						)
						(arc
							(start 0.254 0.1778)
							(mid 0.239121 0.213721)
							(end 0.2032 0.2286)
						)
						(arc
							(start -0.2032 0.2286)
							(mid -0.239121 0.213721)
							(end -0.254 0.1778)
						)
					)
					(width 0)
					(fill yes)
				)
			)
		)
	)
)
